# T6G (Grand Teton) — schematic netlist excerpt (pin names and nets, part order shuffled) for the footprints in the layout excerpt that follows; sources: Cadence DE-HDL packaged netlist, KiCad conversion of 04192023_DAF0TMB3IC0_F0TG_MB_C_brd_V02_OCP.brd

C2383  Q_CAP  22UF 4V 20% X6S  pkg C0402  page 73 : A = PVDDCR_CPU1_P1 ; B = GND
PR303  Q_RES  0 5% CHIP  pkg 0402LF  page 27 : A = SVID_PVDDCR_CPU0_P0_SVD_R ; B = SVID_PVDDCR_CPU0_P0_SVD

(kicad_pcb
	(version 20260206)
	(generator "pcbnew")
	(generator_version "10.0")
	(general
		(thickness 1.6)
		(legacy_teardrops no)
	)
	(paper "A4")
	(title_block
		(title "04192023_DAF0TMB3IC0_F0TG_MB_C_brd_V02_OCP.brd")
		(comment 1 "Grand Teton / footprints 5786-5787 of 8354")
	)
	(layers
		(0 "F.Cu" signal "TOP")
		(4 "In1.Cu" signal "GND")
		(6 "In2.Cu" signal "IN1")
		(8 "In3.Cu" signal "GND1")
		(10 "In4.Cu" signal "IN2")
		(12 "In5.Cu" signal "GND2")
		(14 "In6.Cu" signal "IN3")
		(16 "In7.Cu" signal "GND3")
		(18 "In8.Cu" signal "VCC")
		(20 "In9.Cu" signal "VCC1")
		(22 "In10.Cu" signal "GND4")
		(24 "In11.Cu" signal "IN4")
		(26 "In12.Cu" signal "GND5")
		(28 "In13.Cu" signal "IN5")
		(30 "In14.Cu" signal "GND6")
		(32 "In15.Cu" signal "IN6")
		(34 "In16.Cu" signal "GND7")
		(2 "B.Cu" signal "BOTTOM")
		(9 "F.Adhes" user "F.Adhesive")
		(11 "B.Adhes" user "B.Adhesive")
		(13 "F.Paste" user "Package Geometry/Pastemask Top")
		(15 "B.Paste" user "Package Geometry/Pastemask Bottom")
		(5 "F.SilkS" user "Ref Des/Silkscreen Top")
		(7 "B.SilkS" user "Ref Des/Silkscreen Bottom")
		(1 "F.Mask" user "Board Geometry/Soldermask Top")
		(3 "B.Mask" user "Board Geometry/Soldermask Bottom")
		(17 "Dwgs.User" user "User.Drawings")
		(19 "Cmts.User" user "User.Comments")
		(21 "Eco1.User" user "User.Eco1")
		(23 "Eco2.User" user "User.Eco2")
		(25 "Edge.Cuts" user "Board Geometry/Outline")
		(27 "Margin" user)
		(31 "F.CrtYd" user "Package Geometry/Place Bound Top")
		(29 "B.CrtYd" user "Package Geometry/Place Bound Bottom")
		(35 "F.Fab" user "Ref Des/Assembly Top")
		(33 "B.Fab" user "Ref Des/Assembly Bottom")
	)
	(footprint ""
		(layer "B.Cu")
		(at 368.630962 -214.287608 180)
		(property "Reference" "PR303"
			(at 0 0 0)
			(layer "B.SilkS")
			(hide yes)
			(effects
				(font
					(size 1.27 1.27)
				)
				(justify mirror)
			)
		)
		(property "Value" ""
			(at 0 0 0)
			(layer "B.Fab")
			(effects
				(font
					(size 1.27 1.27)
				)
				(justify mirror)
			)
		)
		(duplicate_pad_numbers_are_jumpers no)
		(fp_line
			(start 0.7874 0.4064)
			(end 0.7874 -0.4064)
			(stroke
				(width 0.1524)
				(type default)
			)
			(layer "B.SilkS")
		)
		(fp_line
			(start 0.7874 -0.4064)
			(end -0.7874 -0.4064)
			(stroke
				(width 0.1524)
				(type default)
			)
			(layer "B.SilkS")
		)
		(fp_line
			(start -0.7874 0.4064)
			(end 0.7874 0.4064)
			(stroke
				(width 0.1524)
				(type default)
			)
			(layer "B.SilkS")
		)
		(fp_line
			(start -0.7874 -0.4064)
			(end -0.7874 0.4064)
			(stroke
				(width 0.1524)
				(type default)
			)
			(layer "B.SilkS")
		)
		(fp_line
			(start 0.67945 0.3048)
			(end 0.67945 -0.305054)
			(stroke
				(width 0.1)
				(type default)
			)
			(layer "B.Fab")
		)
		(fp_line
			(start 0.67945 -0.305054)
			(end 0.12065 -0.305054)
			(stroke
				(width 0.1)
				(type default)
			)
			(layer "B.Fab")
		)
		(fp_line
			(start 0.12065 0.3048)
			(end 0.67945 0.3048)
			(stroke
				(width 0.1)
				(type default)
			)
			(layer "B.Fab")
		)
		(fp_line
			(start 0.12065 0.2794)
			(end 0.12065 0.3048)
			(stroke
				(width 0.1)
				(type default)
			)
			(layer "B.Fab")
		)
		(fp_line
			(start 0.12065 -0.2794)
			(end -0.12065 -0.2794)
			(stroke
				(width 0.1)
				(type default)
			)
			(layer "B.Fab")
		)
		(fp_line
			(start 0.12065 -0.305054)
			(end 0.12065 -0.2794)
			(stroke
				(width 0.1)
				(type default)
			)
			(layer "B.Fab")
		)
		(fp_line
			(start -0.120396 0.3048)
			(end -0.120396 0.2794)
			(stroke
				(width 0.1)
				(type default)
			)
			(layer "B.Fab")
		)
		(fp_line
			(start -0.120396 0.2794)
			(end 0.12065 0.2794)
			(stroke
				(width 0.1)
				(type default)
			)
			(layer "B.Fab")
		)
		(fp_line
			(start -0.12065 -0.2794)
			(end -0.12065 -0.3048)
			(stroke
				(width 0.1)
				(type default)
			)
			(layer "B.Fab")
		)
		(fp_line
			(start -0.12065 -0.3048)
			(end -0.67945 -0.3048)
			(stroke
				(width 0.1)
				(type default)
			)
			(layer "B.Fab")
		)
		(fp_line
			(start -0.67945 0.3048)
			(end -0.120396 0.3048)
			(stroke
				(width 0.1)
				(type default)
			)
			(layer "B.Fab")
		)
		(fp_line
			(start -0.67945 -0.3048)
			(end -0.67945 0.3048)
			(stroke
				(width 0.1)
				(type default)
			)
			(layer "B.Fab")
		)
		(pad "1" smd circle
			(at 0.40005 0)
			(size 0 0)
			(layers "B.Cu" "B.Mask" "B.Paste")
			(net "SVID_PVDDCR_CPU0_P0_SVD_R")
		)
		(pad "2" smd circle
			(at -0.40005 0)
			(size 0 0)
			(layers "B.Cu" "B.Mask" "B.Paste")
			(net "SVID_PVDDCR_CPU0_P0_SVD")
		)
	)
	(footprint ""
		(layer "B.Cu")
		(at 106.085386 -268.418564)
		(property "Reference" "C2383"
			(at 0 0 0)
			(layer "B.SilkS")
			(hide yes)
			(effects
				(font
					(size 1.27 1.27)
				)
				(justify mirror)
			)
		)
		(property "Value" ""
			(at 0 0 0)
			(layer "B.Fab")
			(effects
				(font
					(size 1.27 1.27)
				)
				(justify mirror)
			)
		)
		(duplicate_pad_numbers_are_jumpers no)
		(fp_line
			(start -0.7874 -0.4064)
			(end -0.7874 0.4064)
			(stroke
				(width 0.1524)
				(type default)
			)
			(layer "B.SilkS")
		)
		(fp_line
			(start -0.7874 0.4064)
			(end 0.7874 0.4064)
			(stroke
				(width 0.1524)
				(type default)
			)
			(layer "B.SilkS")
		)
		(fp_line
			(start 0.7874 -0.4064)
			(end -0.7874 -0.4064)
			(stroke
				(width 0.1524)
				(type default)
			)
			(layer "B.SilkS")
		)
		(fp_line
			(start 0.7874 0.4064)
			(end 0.7874 -0.4064)
			(stroke
				(width 0.1524)
				(type default)
			)
			(layer "B.SilkS")
		)
		(fp_line
			(start -0.67945 -0.3048)
			(end -0.67945 0.3048)
			(stroke
				(width 0.1)
				(type default)
			)
			(layer "B.Fab")
		)
		(fp_line
			(start -0.67945 0.3048)
			(end -0.120396 0.3048)
			(stroke
				(width 0.1)
				(type default)
			)
			(layer "B.Fab")
		)
		(fp_line
			(start -0.12065 -0.3048)
			(end -0.67945 -0.3048)
			(stroke
				(width 0.1)
				(type default)
			)
			(layer "B.Fab")
		)
		(fp_line
			(start -0.12065 -0.2794)
			(end -0.12065 -0.3048)
			(stroke
				(width 0.1)
				(type default)
			)
			(layer "B.Fab")
		)
		(fp_line
			(start -0.120396 0.2794)
			(end 0.12065 0.2794)
			(stroke
				(width 0.1)
				(type default)
			)
			(layer "B.Fab")
		)
		(fp_line
			(start -0.120396 0.3048)
			(end -0.120396 0.2794)
			(stroke
				(width 0.1)
				(type default)
			)
			(layer "B.Fab")
		)
		(fp_line
			(start 0.12065 -0.305054)
			(end 0.12065 -0.2794)
			(stroke
				(width 0.1)
				(type default)
			)
			(layer "B.Fab")
		)
		(fp_line
			(start 0.12065 -0.2794)
			(end -0.12065 -0.2794)
			(stroke
				(width 0.1)
				(type default)
			)
			(layer "B.Fab")
		)
		(fp_line
			(start 0.12065 0.2794)
			(end 0.12065 0.3048)
			(stroke
				(width 0.1)
				(type default)
			)
			(layer "B.Fab")
		)
		(fp_line
			(start 0.12065 0.3048)
			(end 0.67945 0.3048)
			(stroke
				(width 0.1)
				(type default)
			)
			(layer "B.Fab")
		)
		(fp_line
			(start 0.67945 -0.305054)
			(end 0.12065 -0.305054)
			(stroke
				(width 0.1)
				(type default)
			)
			(layer "B.Fab")
		)
		(fp_line
			(start 0.67945 0.3048)
			(end 0.67945 -0.305054)
			(stroke
				(width 0.1)
				(type default)
			)
			(layer "B.Fab")
		)
		(pad "1" smd circle
			(at 0.40005 0 180)
			(size 0 0)
			(layers "B.Cu" "B.Mask" "B.Paste")
			(net "PVDDCR_CPU1_P1")
		)
		(pad "2" smd circle
			(at -0.40005 0 180)
			(size 0 0)
			(layers "B.Cu" "B.Mask" "B.Paste")
			(net "GND")
		)
	)
)
